# T6G (Grand Teton) — schematic netlist excerpt (pin names and nets, part order shuffled) for the footprints in the layout excerpt that follows; sources: Cadence DE-HDL packaged netlist, KiCad conversion of 04192023_DAF0TMB3IC0_F0TG_MB_C_brd_V02_OCP.brd

PC288_C0P1_3  Q_CAP  2.2UF 10V 10% X6S  pkg C0402  page 212 : A = PVDDCR_CPU0_P1_PVCC ; B = GND
R6185  Q_RES  10K 1% CHIP  pkg 0402LF  page 83 : A = FM_SEC_MUX_OE_N ; B = GND

(kicad_pcb
	(version 20260206)
	(generator "pcbnew")
	(generator_version "10.0")
	(general
		(thickness 1.6)
		(legacy_teardrops no)
	)
	(paper "A4")
	(title_block
		(title "04192023_DAF0TMB3IC0_F0TG_MB_C_brd_V02_OCP.brd")
		(comment 1 "Grand Teton / footprints 3549-3550 of 8354")
	)
	(layers
		(0 "F.Cu" signal "TOP")
		(4 "In1.Cu" signal "GND")
		(6 "In2.Cu" signal "IN1")
		(8 "In3.Cu" signal "GND1")
		(10 "In4.Cu" signal "IN2")
		(12 "In5.Cu" signal "GND2")
		(14 "In6.Cu" signal "IN3")
		(16 "In7.Cu" signal "GND3")
		(18 "In8.Cu" signal "VCC")
		(20 "In9.Cu" signal "VCC1")
		(22 "In10.Cu" signal "GND4")
		(24 "In11.Cu" signal "IN4")
		(26 "In12.Cu" signal "GND5")
		(28 "In13.Cu" signal "IN5")
		(30 "In14.Cu" signal "GND6")
		(32 "In15.Cu" signal "IN6")
		(34 "In16.Cu" signal "GND7")
		(2 "B.Cu" signal "BOTTOM")
		(9 "F.Adhes" user "F.Adhesive")
		(11 "B.Adhes" user "B.Adhesive")
		(13 "F.Paste" user "Package Geometry/Pastemask Top")
		(15 "B.Paste" user "Package Geometry/Pastemask Bottom")
		(5 "F.SilkS" user "Ref Des/Silkscreen Top")
		(7 "B.SilkS" user "Ref Des/Silkscreen Bottom")
		(1 "F.Mask" user "Board Geometry/Soldermask Top")
		(3 "B.Mask" user "Board Geometry/Soldermask Bottom")
		(17 "Dwgs.User" user "User.Drawings")
		(19 "Cmts.User" user "User.Comments")
		(21 "Eco1.User" user "User.Eco1")
		(23 "Eco2.User" user "User.Eco2")
		(25 "Edge.Cuts" user "Board Geometry/Outline")
		(27 "Margin" user)
		(31 "F.CrtYd" user "Package Geometry/Place Bound Top")
		(29 "B.CrtYd" user "Package Geometry/Place Bound Bottom")
		(35 "F.Fab" user "Ref Des/Assembly Top")
		(33 "B.Fab" user "Ref Des/Assembly Bottom")
	)
	(footprint ""
		(layer "F.Cu")
		(at 102.75697 -182.694834 90)
		(property "Reference" "PC288_C0P1_3"
			(at 0 0 90)
			(layer "F.SilkS")
			(hide yes)
			(effects
				(font
					(size 1.27 1.27)
				)
			)
		)
		(property "Value" ""
			(at 0 0 90)
			(layer "F.Fab")
			(effects
				(font
					(size 1.27 1.27)
				)
			)
		)
		(duplicate_pad_numbers_are_jumpers no)
		(fp_line
			(start 0.7874 -0.4064)
			(end 0.7874 0.4064)
			(stroke
				(width 0.1524)
				(type default)
			)
			(layer "F.SilkS")
		)
		(fp_line
			(start -0.7874 -0.4064)
			(end 0.7874 -0.4064)
			(stroke
				(width 0.1524)
				(type default)
			)
			(layer "F.SilkS")
		)
		(fp_line
			(start 0.7874 0.4064)
			(end -0.7874 0.4064)
			(stroke
				(width 0.1524)
				(type default)
			)
			(layer "F.SilkS")
		)
		(fp_line
			(start -0.7874 0.4064)
			(end -0.7874 -0.4064)
			(stroke
				(width 0.1524)
				(type default)
			)
			(layer "F.SilkS")
		)
		(fp_line
			(start -0.12065 -0.305054)
			(end -0.12065 -0.2794)
			(stroke
				(width 0.1)
				(type default)
			)
			(layer "F.Fab")
		)
		(fp_line
			(start -0.67945 -0.305054)
			(end -0.12065 -0.305054)
			(stroke
				(width 0.1)
				(type default)
			)
			(layer "F.Fab")
		)
		(fp_line
			(start 0.67945 -0.3048)
			(end 0.67945 0.3048)
			(stroke
				(width 0.1)
				(type default)
			)
			(layer "F.Fab")
		)
		(fp_line
			(start 0.12065 -0.3048)
			(end 0.67945 -0.3048)
			(stroke
				(width 0.1)
				(type default)
			)
			(layer "F.Fab")
		)
		(fp_line
			(start 0.12065 -0.2794)
			(end 0.12065 -0.3048)
			(stroke
				(width 0.1)
				(type default)
			)
			(layer "F.Fab")
		)
		(fp_line
			(start -0.12065 -0.2794)
			(end 0.12065 -0.2794)
			(stroke
				(width 0.1)
				(type default)
			)
			(layer "F.Fab")
		)
		(fp_line
			(start 0.120396 0.2794)
			(end -0.12065 0.2794)
			(stroke
				(width 0.1)
				(type default)
			)
			(layer "F.Fab")
		)
		(fp_line
			(start -0.12065 0.2794)
			(end -0.12065 0.3048)
			(stroke
				(width 0.1)
				(type default)
			)
			(layer "F.Fab")
		)
		(fp_line
			(start 0.67945 0.3048)
			(end 0.120396 0.3048)
			(stroke
				(width 0.1)
				(type default)
			)
			(layer "F.Fab")
		)
		(fp_line
			(start 0.120396 0.3048)
			(end 0.120396 0.2794)
			(stroke
				(width 0.1)
				(type default)
			)
			(layer "F.Fab")
		)
		(fp_line
			(start -0.12065 0.3048)
			(end -0.67945 0.3048)
			(stroke
				(width 0.1)
				(type default)
			)
			(layer "F.Fab")
		)
		(fp_line
			(start -0.67945 0.3048)
			(end -0.67945 -0.305054)
			(stroke
				(width 0.1)
				(type default)
			)
			(layer "F.Fab")
		)
		(pad "1" smd circle
			(at -0.40005 0 90)
			(size 0 0)
			(layers "F.Cu" "F.Mask" "F.Paste")
			(net "PVDDCR_CPU0_P1_PVCC")
		)
		(pad "2" smd circle
			(at 0.40005 0 90)
			(size 0 0)
			(layers "F.Cu" "F.Mask" "F.Paste")
			(net "GND")
		)
	)
	(footprint ""
		(layer "F.Cu")
		(at 169.38879 -103.31577 90)
		(property "Reference" "R6185"
			(at 0 0 90)
			(layer "F.SilkS")
			(hide yes)
			(effects
				(font
					(size 1.27 1.27)
				)
			)
		)
		(property "Value" ""
			(at 0 0 90)
			(layer "F.Fab")
			(effects
				(font
					(size 1.27 1.27)
				)
			)
		)
		(duplicate_pad_numbers_are_jumpers no)
		(fp_line
			(start 0.7874 -0.4064)
			(end 0.7874 0.4064)
			(stroke
				(width 0.1524)
				(type default)
			)
			(layer "F.SilkS")
		)
		(fp_line
			(start -0.7874 -0.4064)
			(end 0.7874 -0.4064)
			(stroke
				(width 0.1524)
				(type default)
			)
			(layer "F.SilkS")
		)
		(fp_line
			(start 0.7874 0.4064)
			(end -0.7874 0.4064)
			(stroke
				(width 0.1524)
				(type default)
			)
			(layer "F.SilkS")
		)
		(fp_line
			(start -0.7874 0.4064)
			(end -0.7874 -0.4064)
			(stroke
				(width 0.1524)
				(type default)
			)
			(layer "F.SilkS")
		)
		(fp_line
			(start -0.12065 -0.305054)
			(end -0.12065 -0.2794)
			(stroke
				(width 0.1)
				(type default)
			)
			(layer "F.Fab")
		)
		(fp_line
			(start -0.67945 -0.305054)
			(end -0.12065 -0.305054)
			(stroke
				(width 0.1)
				(type default)
			)
			(layer "F.Fab")
		)
		(fp_line
			(start 0.67945 -0.3048)
			(end 0.67945 0.3048)
			(stroke
				(width 0.1)
				(type default)
			)
			(layer "F.Fab")
		)
		(fp_line
			(start 0.12065 -0.3048)
			(end 0.67945 -0.3048)
			(stroke
				(width 0.1)
				(type default)
			)
			(layer "F.Fab")
		)
		(fp_line
			(start 0.12065 -0.2794)
			(end 0.12065 -0.3048)
			(stroke
				(width 0.1)
				(type default)
			)
			(layer "F.Fab")
		)
		(fp_line
			(start -0.12065 -0.2794)
			(end 0.12065 -0.2794)
			(stroke
				(width 0.1)
				(type default)
			)
			(layer "F.Fab")
		)
		(fp_line
			(start 0.120396 0.2794)
			(end -0.12065 0.2794)
			(stroke
				(width 0.1)
				(type default)
			)
			(layer "F.Fab")
		)
		(fp_line
			(start -0.12065 0.2794)
			(end -0.12065 0.3048)
			(stroke
				(width 0.1)
				(type default)
			)
			(layer "F.Fab")
		)
		(fp_line
			(start 0.67945 0.3048)
			(end 0.120396 0.3048)
			(stroke
				(width 0.1)
				(type default)
			)
			(layer "F.Fab")
		)
		(fp_line
			(start 0.120396 0.3048)
			(end 0.120396 0.2794)
			(stroke
				(width 0.1)
				(type default)
			)
			(layer "F.Fab")
		)
		(fp_line
			(start -0.12065 0.3048)
			(end -0.67945 0.3048)
			(stroke
				(width 0.1)
				(type default)
			)
			(layer "F.Fab")
		)
		(fp_line
			(start -0.67945 0.3048)
			(end -0.67945 -0.305054)
			(stroke
				(width 0.1)
				(type default)
			)
			(layer "F.Fab")
		)
		(pad "1" smd circle
			(at -0.40005 0 90)
			(size 0 0)
			(layers "F.Cu" "F.Mask" "F.Paste")
			(net "FM_SEC_MUX_OE_N")
		)
		(pad "2" smd circle
			(at 0.40005 0 90)
			(size 0 0)
			(layers "F.Cu" "F.Mask" "F.Paste")
			(net "GND")
		)
	)
)
